# BASEBOARD_FAB2 (Tioga Pass) — schematic netlist excerpt (pin names and nets, part order shuffled) for the footprints in the layout excerpt that follows; sources: Cadence DE-HDL packaged netlist, KiCad conversion of Wiwynn_Tioga_Pass_MB.brd

R8W14  RES  0.0 5% CHIP  pkg 0402  page 245 : A = JTAG_RISER_TDO_R ; B = JTAG_RISER_TDO
DS9A1  LED  IC  pkg 1NC  page 175 : C = FP_ID_LED_P5V_STBY_N ; A = FP_ID_LED_XOR_R

(kicad_pcb
	(version 20260206)
	(generator "pcbnew")
	(generator_version "10.0")
	(general
		(thickness 1.6)
		(legacy_teardrops no)
	)
	(paper "A4")
	(title_block
		(title "Wiwynn_Tioga_Pass_MB.brd")
		(comment 1 "Tioga Pass / footprints 887-888 of 4770")
	)
	(layers
		(0 "F.Cu" signal "TOP")
		(4 "In1.Cu" signal "L2GND")
		(6 "In2.Cu" signal "L3")
		(8 "In3.Cu" signal "L4GND")
		(10 "In4.Cu" signal "L5")
		(12 "In5.Cu" signal "L6GND")
		(14 "In6.Cu" signal "L7VCC")
		(16 "In7.Cu" signal "L8VCC")
		(18 "In8.Cu" signal "L9GND")
		(20 "In9.Cu" signal "L10")
		(22 "In10.Cu" signal "L11GND")
		(24 "In11.Cu" signal "L12")
		(26 "In12.Cu" signal "L13GND")
		(2 "B.Cu" signal "BOTTOM")
		(9 "F.Adhes" user "F.Adhesive")
		(11 "B.Adhes" user "B.Adhesive")
		(13 "F.Paste" user "Package Geometry/Pastemask Top")
		(15 "B.Paste" user "Package Geometry/Pastemask Bottom")
		(5 "F.SilkS" user "Ref Des/Silkscreen Top")
		(7 "B.SilkS" user "Ref Des/Silkscreen Bottom")
		(1 "F.Mask" user "Board Geometry/Soldermask Top")
		(3 "B.Mask" user "Board Geometry/Soldermask Bottom")
		(17 "Dwgs.User" user "User.Drawings")
		(19 "Cmts.User" user "User.Comments")
		(21 "Eco1.User" user "User.Eco1")
		(23 "Eco2.User" user "User.Eco2")
		(25 "Edge.Cuts" user "Board Geometry/Outline")
		(27 "Margin" user)
		(31 "F.CrtYd" user "Package Geometry/Place Bound Top")
		(29 "B.CrtYd" user "Package Geometry/Place Bound Bottom")
		(35 "F.Fab" user "Ref Des/Assembly Top")
		(33 "B.Fab" user "Ref Des/Assembly Bottom")
	)
	(footprint ""
		(layer "F.Cu")
		(at 499.872 -155.321)
		(property "Reference" "DS9A1"
			(at -0.49276 -1.47447 0)
			(unlocked yes)
			(layer "F.SilkS")
			(effects
				(font
					(size 0.7874 0.5842)
					(thickness 0.1524)
				)
			)
		)
		(property "Value" ""
			(at 0 0 0)
			(layer "F.Fab")
			(effects
				(font
					(size 1.27 1.27)
				)
			)
		)
		(duplicate_pad_numbers_are_jumpers no)
		(fp_line
			(start -1.728978 -0.9525)
			(end -1.248156 -1.785366)
			(stroke
				(width 0.1524)
				(type default)
			)
			(layer "F.SilkS")
		)
		(fp_line
			(start -1.248156 -2.908808)
			(end -1.248156 -1.785366)
			(stroke
				(width 0.1524)
				(type default)
			)
			(layer "F.SilkS")
		)
		(fp_line
			(start -1.248156 -1.785366)
			(end -0.767334 -0.9525)
			(stroke
				(width 0.1524)
				(type default)
			)
			(layer "F.SilkS")
		)
		(fp_line
			(start -1.248156 -0.9525)
			(end -1.728978 -0.9525)
			(stroke
				(width 0.1524)
				(type default)
			)
			(layer "F.SilkS")
		)
		(fp_line
			(start -1.248156 -0.040894)
			(end -1.248156 -0.9525)
			(stroke
				(width 0.1524)
				(type default)
			)
			(layer "F.SilkS")
		)
		(fp_line
			(start -0.767334 -1.785366)
			(end -1.728978 -1.785366)
			(stroke
				(width 0.1524)
				(type default)
			)
			(layer "F.SilkS")
		)
		(fp_line
			(start -0.767334 -0.9525)
			(end -1.248156 -0.9525)
			(stroke
				(width 0.1524)
				(type default)
			)
			(layer "F.SilkS")
		)
		(fp_poly
			(pts
				(xy -0.5715 2.2098) (xy -0.5715 0.2032) (xy 0.5715 0.2032) (xy 0.5715 0.6985)
				(arc
					(start 0.726948 0.6985)
					(mid 1.29058 0.932279)
					(end 1.524 1.49606)
				)
				(arc
					(start 1.524 2.05994)
					(mid 1.2904 2.6239)
					(end 0.72644 2.8575)
				)
				(xy 0.5715 2.8575) (xy 0.5715 3.3528) (xy -0.5715 3.3528)
			)
			(stroke
				(width 0)
				(type default)
			)
			(fill no)
			(layer "F.CrtYd")
		)
		(fp_line
			(start -1.720088 -0.958342)
			(end -1.239266 -1.791208)
			(stroke
				(width 0.1)
				(type default)
			)
			(layer "F.Fab")
		)
		(fp_line
			(start -1.239266 -1.791208)
			(end -1.239266 -2.91465)
			(stroke
				(width 0.1)
				(type default)
			)
			(layer "F.Fab")
		)
		(fp_line
			(start -1.239266 -1.791208)
			(end -0.758444 -0.958342)
			(stroke
				(width 0.1)
				(type default)
			)
			(layer "F.Fab")
		)
		(fp_line
			(start -1.239266 -0.958342)
			(end -1.239266 -0.046736)
			(stroke
				(width 0.1)
				(type default)
			)
			(layer "F.Fab")
		)
		(fp_line
			(start -0.758444 -1.791208)
			(end -1.720088 -1.791208)
			(stroke
				(width 0.1)
				(type default)
			)
			(layer "F.Fab")
		)
		(fp_line
			(start -0.758444 -0.958342)
			(end -1.720088 -0.958342)
			(stroke
				(width 0.1)
				(type default)
			)
			(layer "F.Fab")
		)
		(fp_line
			(start -0.5715 0.2032)
			(end 0.5715 0.2032)
			(stroke
				(width 0.1)
				(type default)
			)
			(layer "F.Fab")
		)
		(fp_line
			(start -0.5715 0.7112)
			(end 0.5715 0.7112)
			(stroke
				(width 0.1)
				(type default)
			)
			(layer "F.Fab")
		)
		(fp_line
			(start -0.5715 2.8448)
			(end 0.5715 2.8448)
			(stroke
				(width 0.1)
				(type default)
			)
			(layer "F.Fab")
		)
		(fp_line
			(start -0.5715 3.3528)
			(end -0.5715 0.2032)
			(stroke
				(width 0.1)
				(type default)
			)
			(layer "F.Fab")
		)
		(fp_line
			(start 0.5715 0.2032)
			(end 0.5715 3.3528)
			(stroke
				(width 0.1)
				(type default)
			)
			(layer "F.Fab")
		)
		(fp_line
			(start 0.5715 2.8575)
			(end 0.72644 2.8575)
			(stroke
				(width 0.1)
				(type default)
			)
			(layer "F.Fab")
		)
		(fp_line
			(start 0.5715 3.3528)
			(end -0.5715 3.3528)
			(stroke
				(width 0.1)
				(type default)
			)
			(layer "F.Fab")
		)
		(fp_line
			(start 0.72644 0.6985)
			(end 0.5715 0.6985)
			(stroke
				(width 0.1)
				(type default)
			)
			(layer "F.Fab")
		)
		(fp_line
			(start 1.524 2.05994)
			(end 1.524 1.49606)
			(stroke
				(width 0.1)
				(type default)
			)
			(layer "F.Fab")
		)
		(fp_arc
			(start 0.72644 0.6985)
			(mid 1.290388 0.932112)
			(end 1.524 1.49606)
			(stroke
				(width 0.1)
				(type default)
			)
			(layer "F.Fab")
		)
		(fp_arc
			(start 1.524 2.05994)
			(mid 1.290388 2.623888)
			(end 0.72644 2.8575)
			(stroke
				(width 0.1)
				(type default)
			)
			(layer "F.Fab")
		)
		(pad "1" smd rect
			(at 0 0)
			(size 1.524 1.524)
			(layers "F.Cu" "F.Mask" "F.Paste")
			(net "FP_ID_LED_P5V_STBY_N")
		)
		(pad "2" smd rect
			(at 0 3.556)
			(size 1.524 1.524)
			(layers "F.Cu" "F.Mask" "F.Paste")
			(net "FP_ID_LED_XOR_R")
		)
		(pad "3" smd rect
			(at -0.762 1.778)
			(size 0.889 0.889)
			(layers "F.Cu" "F.Mask" "F.Paste")
			(net "Net_6474")
		)
		(zone
			(layer "F.Cu")
			(hatch none 0.5)
			(connect_pads
				(clearance 0)
			)
			(min_thickness 0.25)
			(keepout
				(tracks allowed)
				(vias not_allowed)
				(pads allowed)
				(copperpour not_allowed)
				(footprints allowed)
			)
			(placement
				(enabled no)
				(sheetname "")
			)
			(fill
				(thermal_gap 0.5)
				(thermal_bridge_width 0.5)
				(island_removal_mode 0)
			)
			(polygon
				(pts
					(xy 500.4435 -154.5082) (xy 500.4435 -152.5778) (xy 499.3005 -152.5778) (xy 499.3005 -154.5082)
				)
			)
		)
	)
	(footprint ""
		(layer "F.Cu")
		(at 359.876598 -10.916158)
		(property "Reference" "R8W14"
			(at -0.8382 -0.67818 0)
			(unlocked yes)
			(layer "F.SilkS")
			(effects
				(font
					(size 0.4064 0.254)
					(thickness 0.1524)
				)
				(justify left)
			)
		)
		(property "Value" ""
			(at 0 0 0)
			(layer "F.Fab")
			(effects
				(font
					(size 1.27 1.27)
				)
			)
		)
		(duplicate_pad_numbers_are_jumpers no)
		(fp_poly
			(pts
				(xy -0.2794 -0.1016) (xy 0.2794 -0.1016) (xy 0.2794 0.9906) (xy -0.2794 0.9906)
			)
			(stroke
				(width 0)
				(type default)
			)
			(fill no)
			(layer "F.CrtYd")
		)
		(fp_line
			(start -0.2794 -0.1016)
			(end -0.2794 0.9906)
			(stroke
				(width 0.1)
				(type default)
			)
			(layer "F.Fab")
		)
		(fp_line
			(start -0.2794 0.9906)
			(end 0.2794 0.9906)
			(stroke
				(width 0.1)
				(type default)
			)
			(layer "F.Fab")
		)
		(fp_line
			(start 0.2794 -0.1016)
			(end -0.2794 -0.1016)
			(stroke
				(width 0.1)
				(type default)
			)
			(layer "F.Fab")
		)
		(fp_line
			(start 0.2794 0.9906)
			(end 0.2794 -0.1016)
			(stroke
				(width 0.1)
				(type default)
			)
			(layer "F.Fab")
		)
		(pad "1" smd rect
			(at 0 0)
			(size 0.508 0.508)
			(layers "F.Cu" "F.Mask" "F.Paste")
			(net "JTAG_RISER_TDO_R")
		)
		(pad "2" smd rect
			(at 0 0.889)
			(size 0.508 0.508)
			(layers "F.Cu" "F.Mask" "F.Paste")
			(net "JTAG_RISER_TDO")
		)
		(zone
			(layer "F.Cu")
			(hatch none 0.5)
			(connect_pads
				(clearance 0)
			)
			(min_thickness 0.25)
			(keepout
				(tracks allowed)
				(vias not_allowed)
				(pads allowed)
				(copperpour not_allowed)
				(footprints allowed)
			)
			(placement
				(enabled no)
				(sheetname "")
			)
			(fill
				(thermal_gap 0.5)
				(thermal_bridge_width 0.5)
				(island_removal_mode 0)
			)
			(polygon
				(pts
					(xy 359.622598 -10.662158) (xy 360.130598 -10.662158) (xy 360.130598 -10.281158) (xy 359.622598 -10.281158)
				)
			)
		)
		(zone
			(layer "F.Cu")
			(hatch none 0.5)
			(connect_pads
				(clearance 0)
			)
			(min_thickness 0.25)
			(keepout
				(tracks not_allowed)
				(vias allowed)
				(pads allowed)
				(copperpour not_allowed)
				(footprints allowed)
			)
			(placement
				(enabled no)
				(sheetname "")
			)
			(fill
				(thermal_gap 0.5)
				(thermal_bridge_width 0.5)
				(island_removal_mode 0)
			)
			(polygon
				(pts
					(xy 359.622598 -10.281158) (xy 360.130598 -10.281158) (xy 360.130598 -10.662158) (xy 359.622598 -10.662158)
				)
			)
		)
	)
)
